# S9S_MB_2U (Grand Teton) — schematic netlist excerpt (pin names and nets, part order shuffled) for the footprints in the layout excerpt that follows; sources: Cadence DE-HDL packaged netlist, KiCad conversion of 03242023_DA0F0TMBIJ0_F0T_Motherboard_J_brd_V01_OCP.brd

C1403  Q_CAP  47UF 4V 20% X6S  pkg C0805  page 79 : A = PVNN_MAIN_CPU1 ; B = GND
R2560  Q_RES  0 5% CHIP  pkg 0402LF  page 292 : A = SVID_DIO0_CPU1_R ; B = SVID_DIO_PVCCINFAON_CPU1_R
R2363  Q_RES  10 1% CHIP  pkg 0402LF  page 202 : A = RST_ESPI_RESET_N ; B = RST_ESPI_RESET_N_R

(kicad_pcb
	(version 20260206)
	(generator "pcbnew")
	(generator_version "10.0")
	(general
		(thickness 1.6)
		(legacy_teardrops no)
	)
	(paper "A4")
	(title_block
		(title "03242023_DA0F0TMBIJ0_F0T_Motherboard_J_brd_V01_OCP.brd")
		(comment 1 "Grand Teton / footprints 3399-3401 of 6105")
	)
	(layers
		(0 "F.Cu" signal "TOP")
		(4 "In1.Cu" signal "GND")
		(6 "In2.Cu" signal "IN1")
		(8 "In3.Cu" signal "GND1")
		(10 "In4.Cu" signal "IN2")
		(12 "In5.Cu" signal "GND2")
		(14 "In6.Cu" signal "IN3")
		(16 "In7.Cu" signal "GND3")
		(18 "In8.Cu" signal "VCC")
		(20 "In9.Cu" signal "VCC1")
		(22 "In10.Cu" signal "GND4")
		(24 "In11.Cu" signal "IN4")
		(26 "In12.Cu" signal "GND5")
		(28 "In13.Cu" signal "IN5")
		(30 "In14.Cu" signal "GND6")
		(32 "In15.Cu" signal "IN6")
		(34 "In16.Cu" signal "GND7")
		(2 "B.Cu" signal "BOTTOM")
		(9 "F.Adhes" user "F.Adhesive")
		(11 "B.Adhes" user "B.Adhesive")
		(13 "F.Paste" user "Package Geometry/Pastemask Top")
		(15 "B.Paste" user "Package Geometry/Pastemask Bottom")
		(5 "F.SilkS" user "Ref Des/Silkscreen Top")
		(7 "B.SilkS" user "Ref Des/Silkscreen Bottom")
		(1 "F.Mask" user "Board Geometry/Soldermask Top")
		(3 "B.Mask" user "Board Geometry/Soldermask Bottom")
		(17 "Dwgs.User" user "User.Drawings")
		(19 "Cmts.User" user "User.Comments")
		(21 "Eco1.User" user "User.Eco1")
		(23 "Eco2.User" user "User.Eco2")
		(25 "Edge.Cuts" user "Board Geometry/Outline")
		(27 "Margin" user)
		(31 "F.CrtYd" user "Package Geometry/Place Bound Top")
		(29 "B.CrtYd" user "Package Geometry/Place Bound Bottom")
		(35 "F.Fab" user "Ref Des/Assembly Top")
		(33 "B.Fab" user "Ref Des/Assembly Bottom")
	)
	(footprint ""
		(layer "F.Cu")
		(at 36.956238 -130.76174 180)
		(property "Reference" "R2560"
			(at 0 0 180)
			(layer "F.SilkS")
			(hide yes)
			(effects
				(font
					(size 1.27 1.27)
				)
			)
		)
		(property "Value" ""
			(at 0 0 180)
			(layer "F.Fab")
			(effects
				(font
					(size 1.27 1.27)
				)
			)
		)
		(duplicate_pad_numbers_are_jumpers no)
		(fp_line
			(start 0.7874 0.4064)
			(end -0.7874 0.4064)
			(stroke
				(width 0.1524)
				(type default)
			)
			(layer "F.SilkS")
		)
		(fp_line
			(start 0.7874 -0.4064)
			(end 0.7874 0.4064)
			(stroke
				(width 0.1524)
				(type default)
			)
			(layer "F.SilkS")
		)
		(fp_line
			(start -0.7874 0.4064)
			(end -0.7874 -0.4064)
			(stroke
				(width 0.1524)
				(type default)
			)
			(layer "F.SilkS")
		)
		(fp_line
			(start -0.7874 -0.4064)
			(end 0.7874 -0.4064)
			(stroke
				(width 0.1524)
				(type default)
			)
			(layer "F.SilkS")
		)
		(fp_line
			(start 0.67945 0.3048)
			(end 0.120396 0.3048)
			(stroke
				(width 0.1)
				(type default)
			)
			(layer "F.Fab")
		)
		(fp_line
			(start 0.67945 -0.3048)
			(end 0.67945 0.3048)
			(stroke
				(width 0.1)
				(type default)
			)
			(layer "F.Fab")
		)
		(fp_line
			(start 0.12065 -0.2794)
			(end 0.12065 -0.3048)
			(stroke
				(width 0.1)
				(type default)
			)
			(layer "F.Fab")
		)
		(fp_line
			(start 0.12065 -0.3048)
			(end 0.67945 -0.3048)
			(stroke
				(width 0.1)
				(type default)
			)
			(layer "F.Fab")
		)
		(fp_line
			(start 0.120396 0.3048)
			(end 0.120396 0.2794)
			(stroke
				(width 0.1)
				(type default)
			)
			(layer "F.Fab")
		)
		(fp_line
			(start 0.120396 0.2794)
			(end -0.12065 0.2794)
			(stroke
				(width 0.1)
				(type default)
			)
			(layer "F.Fab")
		)
		(fp_line
			(start -0.12065 0.3048)
			(end -0.67945 0.3048)
			(stroke
				(width 0.1)
				(type default)
			)
			(layer "F.Fab")
		)
		(fp_line
			(start -0.12065 0.2794)
			(end -0.12065 0.3048)
			(stroke
				(width 0.1)
				(type default)
			)
			(layer "F.Fab")
		)
		(fp_line
			(start -0.12065 -0.2794)
			(end 0.12065 -0.2794)
			(stroke
				(width 0.1)
				(type default)
			)
			(layer "F.Fab")
		)
		(fp_line
			(start -0.12065 -0.305054)
			(end -0.12065 -0.2794)
			(stroke
				(width 0.1)
				(type default)
			)
			(layer "F.Fab")
		)
		(fp_line
			(start -0.67945 0.3048)
			(end -0.67945 -0.305054)
			(stroke
				(width 0.1)
				(type default)
			)
			(layer "F.Fab")
		)
		(fp_line
			(start -0.67945 -0.305054)
			(end -0.12065 -0.305054)
			(stroke
				(width 0.1)
				(type default)
			)
			(layer "F.Fab")
		)
		(pad "1" smd circle
			(at -0.40005 0 180)
			(size 0 0)
			(layers "F.Cu" "F.Mask" "F.Paste")
			(net "SVID_DIO0_CPU1_R")
		)
		(pad "2" smd circle
			(at 0.40005 0 180)
			(size 0 0)
			(layers "F.Cu" "F.Mask" "F.Paste")
			(net "SVID_DIO_PVCCINFAON_CPU1_R")
		)
	)
	(footprint ""
		(layer "F.Cu")
		(at 40.300402 -180.55336 180)
		(property "Reference" "C1403"
			(at 0 0 180)
			(layer "F.SilkS")
			(hide yes)
			(effects
				(font
					(size 1.27 1.27)
				)
			)
		)
		(property "Value" ""
			(at 0 0 180)
			(layer "F.Fab")
			(effects
				(font
					(size 1.27 1.27)
				)
			)
		)
		(duplicate_pad_numbers_are_jumpers no)
		(fp_line
			(start 1.524 0.762)
			(end -1.524 0.762)
			(stroke
				(width 0.1524)
				(type default)
			)
			(layer "F.SilkS")
		)
		(fp_line
			(start 1.524 -0.762)
			(end 1.524 0.762)
			(stroke
				(width 0.1524)
				(type default)
			)
			(layer "F.SilkS")
		)
		(fp_line
			(start -1.524 0.762)
			(end -1.524 -0.762)
			(stroke
				(width 0.1524)
				(type default)
			)
			(layer "F.SilkS")
		)
		(fp_line
			(start -1.524 -0.762)
			(end 1.524 -0.762)
			(stroke
				(width 0.1524)
				(type default)
			)
			(layer "F.SilkS")
		)
		(fp_line
			(start 1.1049 0.724916)
			(end 1.1049 -0.724916)
			(stroke
				(width 0.1)
				(type default)
			)
			(layer "F.Fab")
		)
		(fp_line
			(start 1.1049 -0.724916)
			(end -1.1049 -0.724916)
			(stroke
				(width 0.1)
				(type default)
			)
			(layer "F.Fab")
		)
		(fp_line
			(start -1.1049 0.724916)
			(end 1.1049 0.724916)
			(stroke
				(width 0.1)
				(type default)
			)
			(layer "F.Fab")
		)
		(fp_line
			(start -1.1049 -0.724916)
			(end -1.1049 0.724916)
			(stroke
				(width 0.1)
				(type default)
			)
			(layer "F.Fab")
		)
		(pad "1" smd rect
			(at -0.889 0)
			(size 1.016 1.27)
			(layers "F.Cu" "F.Mask" "F.Paste")
			(net "PVNN_MAIN_CPU1")
		)
		(pad "2" smd rect
			(at 0.889 0)
			(size 1.016 1.27)
			(layers "F.Cu" "F.Mask" "F.Paste")
			(net "GND")
		)
	)
	(footprint ""
		(layer "F.Cu")
		(at 332.433168 -23.571454 -90)
		(property "Reference" "R2363"
			(at 0 0 270)
			(layer "F.SilkS")
			(hide yes)
			(effects
				(font
					(size 1.27 1.27)
				)
			)
		)
		(property "Value" ""
			(at 0 0 270)
			(layer "F.Fab")
			(effects
				(font
					(size 1.27 1.27)
				)
			)
		)
		(duplicate_pad_numbers_are_jumpers no)
		(fp_line
			(start -0.7874 0.4064)
			(end -0.7874 -0.4064)
			(stroke
				(width 0.1524)
				(type default)
			)
			(layer "F.SilkS")
		)
		(fp_line
			(start 0.7874 0.4064)
			(end -0.7874 0.4064)
			(stroke
				(width 0.1524)
				(type default)
			)
			(layer "F.SilkS")
		)
		(fp_line
			(start -0.7874 -0.4064)
			(end 0.7874 -0.4064)
			(stroke
				(width 0.1524)
				(type default)
			)
			(layer "F.SilkS")
		)
		(fp_line
			(start 0.7874 -0.4064)
			(end 0.7874 0.4064)
			(stroke
				(width 0.1524)
				(type default)
			)
			(layer "F.SilkS")
		)
		(fp_line
			(start -0.67945 0.3048)
			(end -0.67945 -0.305054)
			(stroke
				(width 0.1)
				(type default)
			)
			(layer "F.Fab")
		)
		(fp_line
			(start -0.12065 0.3048)
			(end -0.67945 0.3048)
			(stroke
				(width 0.1)
				(type default)
			)
			(layer "F.Fab")
		)
		(fp_line
			(start 0.120396 0.3048)
			(end 0.120396 0.2794)
			(stroke
				(width 0.1)
				(type default)
			)
			(layer "F.Fab")
		)
		(fp_line
			(start 0.67945 0.3048)
			(end 0.120396 0.3048)
			(stroke
				(width 0.1)
				(type default)
			)
			(layer "F.Fab")
		)
		(fp_line
			(start -0.12065 0.2794)
			(end -0.12065 0.3048)
			(stroke
				(width 0.1)
				(type default)
			)
			(layer "F.Fab")
		)
		(fp_line
			(start 0.120396 0.2794)
			(end -0.12065 0.2794)
			(stroke
				(width 0.1)
				(type default)
			)
			(layer "F.Fab")
		)
		(fp_line
			(start -0.12065 -0.2794)
			(end 0.12065 -0.2794)
			(stroke
				(width 0.1)
				(type default)
			)
			(layer "F.Fab")
		)
		(fp_line
			(start 0.12065 -0.2794)
			(end 0.12065 -0.3048)
			(stroke
				(width 0.1)
				(type default)
			)
			(layer "F.Fab")
		)
		(fp_line
			(start 0.12065 -0.3048)
			(end 0.67945 -0.3048)
			(stroke
				(width 0.1)
				(type default)
			)
			(layer "F.Fab")
		)
		(fp_line
			(start 0.67945 -0.3048)
			(end 0.67945 0.3048)
			(stroke
				(width 0.1)
				(type default)
			)
			(layer "F.Fab")
		)
		(fp_line
			(start -0.67945 -0.305054)
			(end -0.12065 -0.305054)
			(stroke
				(width 0.1)
				(type default)
			)
			(layer "F.Fab")
		)
		(fp_line
			(start -0.12065 -0.305054)
			(end -0.12065 -0.2794)
			(stroke
				(width 0.1)
				(type default)
			)
			(layer "F.Fab")
		)
		(pad "1" smd circle
			(at -0.40005 0 270)
			(size 0 0)
			(layers "F.Cu" "F.Mask" "F.Paste")
			(net "RST_ESPI_RESET_N")
		)
		(pad "2" smd circle
			(at 0.40005 0 270)
			(size 0 0)
			(layers "F.Cu" "F.Mask" "F.Paste")
			(net "RST_ESPI_RESET_N_R")
		)
	)
)
